FILE_TYPE=LIBRARY_PARTS;
TIME=' Created/Modified on Fri Sep 25 16:24:18 2009' ;
primitive 'PCA9555PW';
  pin
    '-INT':
      PIN_NUMBER='(1)';
      OUTPUT_LOAD='(1.0,-1.0)';
    'SDA':
      PIN_NUMBER='(23)';
      INPUT_LOAD='(-0.01,0.01)';
      OUTPUT_LOAD='(1.0,-1.0)';
      BIDIRECTIONAL='TRUE';
    'SCL':
      PIN_NUMBER='(22)';
      INPUT_LOAD='(-0.01,0.01)';
      OUTPUT_LOAD='(1.0,-1.0)';
      BIDIRECTIONAL='TRUE';
    'P00':
      PIN_NUMBER='(4)';
      INPUT_LOAD='(-0.01,0.01)';
      OUTPUT_LOAD='(1.0,-1.0)';
      BIDIRECTIONAL='TRUE';
    'P01':
      PIN_NUMBER='(5)';
      INPUT_LOAD='(-0.01,0.01)';
      OUTPUT_LOAD='(1.0,-1.0)';
      BIDIRECTIONAL='TRUE';
    'P02':
      PIN_NUMBER='(6)';
      INPUT_LOAD='(-0.01,0.01)';
      OUTPUT_LOAD='(1.0,-1.0)';
      BIDIRECTIONAL='TRUE';
    'P03':
      PIN_NUMBER='(7)';
      INPUT_LOAD='(-0.01,0.01)';
      OUTPUT_LOAD='(1.0,-1.0)';
      BIDIRECTIONAL='TRUE';
    'P04':
      PIN_NUMBER='(8)';
      INPUT_LOAD='(-0.01,0.01)';
      OUTPUT_LOAD='(1.0,-1.0)';
      BIDIRECTIONAL='TRUE';
    'P05':
      PIN_NUMBER='(9)';
      INPUT_LOAD='(-0.01,0.01)';
      OUTPUT_LOAD='(1.0,-1.0)';
      BIDIRECTIONAL='TRUE';
    'P06':
      PIN_NUMBER='(10)';
      INPUT_LOAD='(-0.01,0.01)';
      OUTPUT_LOAD='(1.0,-1.0)';
      BIDIRECTIONAL='TRUE';
    'P07':
      PIN_NUMBER='(11)';
      INPUT_LOAD='(-0.01,0.01)';
      OUTPUT_LOAD='(1.0,-1.0)';
      BIDIRECTIONAL='TRUE';
    'P10':
      PIN_NUMBER='(13)';
      INPUT_LOAD='(-0.01,0.01)';
      OUTPUT_LOAD='(1.0,-1.0)';
      BIDIRECTIONAL='TRUE';
    'P11':
      PIN_NUMBER='(14)';
      INPUT_LOAD='(-0.01,0.01)';
      OUTPUT_LOAD='(1.0,-1.0)';
      BIDIRECTIONAL='TRUE';
    'P12':
      PIN_NUMBER='(15)';
      INPUT_LOAD='(-0.01,0.01)';
      OUTPUT_LOAD='(1.0,-1.0)';
      BIDIRECTIONAL='TRUE';
    'P13':
      PIN_NUMBER='(16)';
      INPUT_LOAD='(-0.01,0.01)';
      OUTPUT_LOAD='(1.0,-1.0)';
      BIDIRECTIONAL='TRUE';
    'P14':
      PIN_NUMBER='(17)';
      INPUT_LOAD='(-0.01,0.01)';
      OUTPUT_LOAD='(1.0,-1.0)';
      BIDIRECTIONAL='TRUE';
    'P15':
      PIN_NUMBER='(18)';
      INPUT_LOAD='(-0.01,0.01)';
      OUTPUT_LOAD='(1.0,-1.0)';
      BIDIRECTIONAL='TRUE';
    'P16':
      PIN_NUMBER='(19)';
      INPUT_LOAD='(-0.01,0.01)';
      OUTPUT_LOAD='(1.0,-1.0)';
      BIDIRECTIONAL='TRUE';
    'P17':
      PIN_NUMBER='(20)';
      INPUT_LOAD='(-0.01,0.01)';
      OUTPUT_LOAD='(1.0,-1.0)';
      BIDIRECTIONAL='TRUE';
    'A0':
      PIN_NUMBER='(21)';
      INPUT_LOAD='(-0.01,0.01)';
      OUTPUT_LOAD='(1.0,-1.0)';
      BIDIRECTIONAL='TRUE';
    'A1':
      PIN_NUMBER='(2)';
      INPUT_LOAD='(-0.01,0.01)';
      OUTPUT_LOAD='(1.0,-1.0)';
      BIDIRECTIONAL='TRUE';
    'A2':
      PIN_NUMBER='(3)';
      INPUT_LOAD='(-0.01,0.01)';
      OUTPUT_LOAD='(1.0,-1.0)';
      BIDIRECTIONAL='TRUE';
    'VDD':
      PIN_NUMBER='(24)';
      PINUSE='POWER';
    'VSS':
      PIN_NUMBER='(12)';
      PINUSE='POWER';
  end_pin;
  body
    CLASS='IC';
    PART_NAME='PCA9555PW';
    PHYS_DES_PREFIX='U';
    JEDEC_TYPE='TSSOP-16';
  end_body;
end_primitive;
END.
